(kicad_pcb
	(version 20260206)
	(generator "pcbnew")
	(generator_version "10.0")
	(general
		(thickness 1.6)
		(legacy_teardrops no)
	)
	(paper "A4")
	(title_block
		(title "03242023_DA0F0TMBIJ0_F0T_Motherboard_J_brd_V01_OCP.brd")
		(comment 1 "Grand Teton / footprints 3256-3261 of 6105")
	)
	(layers
		(0 "F.Cu" signal "TOP")
		(4 "In1.Cu" signal "GND")
		(6 "In2.Cu" signal "IN1")
		(8 "In3.Cu" signal "GND1")
		(10 "In4.Cu" signal "IN2")
		(12 "In5.Cu" signal "GND2")
		(14 "In6.Cu" signal "IN3")
		(16 "In7.Cu" signal "GND3")
		(18 "In8.Cu" signal "VCC")
		(20 "In9.Cu" signal "VCC1")
		(22 "In10.Cu" signal "GND4")
		(24 "In11.Cu" signal "IN4")
		(26 "In12.Cu" signal "GND5")
		(28 "In13.Cu" signal "IN5")
		(30 "In14.Cu" signal "GND6")
		(32 "In15.Cu" signal "IN6")
		(34 "In16.Cu" signal "GND7")
		(2 "B.Cu" signal "BOTTOM")
		(9 "F.Adhes" user "F.Adhesive")
		(11 "B.Adhes" user "B.Adhesive")
		(13 "F.Paste" user "Package Geometry/Pastemask Top")
		(15 "B.Paste" user "Package Geometry/Pastemask Bottom")
		(5 "F.SilkS" user "Ref Des/Silkscreen Top")
		(7 "B.SilkS" user "Ref Des/Silkscreen Bottom")
		(1 "F.Mask" user "Board Geometry/Soldermask Top")
		(3 "B.Mask" user "Board Geometry/Soldermask Bottom")
		(17 "Dwgs.User" user "User.Drawings")
		(19 "Cmts.User" user "User.Comments")
		(21 "Eco1.User" user "User.Eco1")
		(23 "Eco2.User" user "User.Eco2")
		(25 "Edge.Cuts" user "Board Geometry/Outline")
		(27 "Margin" user)
		(31 "F.CrtYd" user "Package Geometry/Place Bound Top")
		(29 "B.CrtYd" user "Package Geometry/Place Bound Bottom")
		(35 "F.Fab" user "Ref Des/Assembly Top")
		(33 "B.Fab" user "Ref Des/Assembly Bottom")
	)
	(footprint ""
		(layer "F.Cu")
		(at 107.307634 -247.715278 90)
		(property "Reference" "C295"
			(at 0 0 90)
			(layer "F.SilkS")
			(hide yes)
			(effects
				(font
					(size 1.27 1.27)
				)
			)
		)
		(property "Value" ""
			(at 0 0 90)
			(layer "F.Fab")
			(effects
				(font
					(size 1.27 1.27)
				)
			)
		)
		(duplicate_pad_numbers_are_jumpers no)
		(fp_line
			(start 0.7874 -0.4064)
			(end 0.7874 0.4064)
			(stroke
				(width 0.1524)
				(type default)
			)
			(layer "F.SilkS")
		)
		(fp_line
			(start -0.7874 -0.4064)
			(end 0.7874 -0.4064)
			(stroke
				(width 0.1524)
				(type default)
			)
			(layer "F.SilkS")
		)
		(fp_line
			(start 0.7874 0.4064)
			(end -0.7874 0.4064)
			(stroke
				(width 0.1524)
				(type default)
			)
			(layer "F.SilkS")
		)
		(fp_line
			(start -0.7874 0.4064)
			(end -0.7874 -0.4064)
			(stroke
				(width 0.1524)
				(type default)
			)
			(layer "F.SilkS")
		)
		(fp_line
			(start -0.12065 -0.305054)
			(end -0.12065 -0.2794)
			(stroke
				(width 0.1)
				(type default)
			)
			(layer "F.Fab")
		)
		(fp_line
			(start -0.67945 -0.305054)
			(end -0.12065 -0.305054)
			(stroke
				(width 0.1)
				(type default)
			)
			(layer "F.Fab")
		)
		(fp_line
			(start 0.67945 -0.3048)
			(end 0.67945 0.3048)
			(stroke
				(width 0.1)
				(type default)
			)
			(layer "F.Fab")
		)
		(fp_line
			(start 0.12065 -0.3048)
			(end 0.67945 -0.3048)
			(stroke
				(width 0.1)
				(type default)
			)
			(layer "F.Fab")
		)
		(fp_line
			(start 0.12065 -0.2794)
			(end 0.12065 -0.3048)
			(stroke
				(width 0.1)
				(type default)
			)
			(layer "F.Fab")
		)
		(fp_line
			(start -0.12065 -0.2794)
			(end 0.12065 -0.2794)
			(stroke
				(width 0.1)
				(type default)
			)
			(layer "F.Fab")
		)
		(fp_line
			(start 0.120396 0.2794)
			(end -0.12065 0.2794)
			(stroke
				(width 0.1)
				(type default)
			)
			(layer "F.Fab")
		)
		(fp_line
			(start -0.12065 0.2794)
			(end -0.12065 0.3048)
			(stroke
				(width 0.1)
				(type default)
			)
			(layer "F.Fab")
		)
		(fp_line
			(start 0.67945 0.3048)
			(end 0.120396 0.3048)
			(stroke
				(width 0.1)
				(type default)
			)
			(layer "F.Fab")
		)
		(fp_line
			(start 0.120396 0.3048)
			(end 0.120396 0.2794)
			(stroke
				(width 0.1)
				(type default)
			)
			(layer "F.Fab")
		)
		(fp_line
			(start -0.12065 0.3048)
			(end -0.67945 0.3048)
			(stroke
				(width 0.1)
				(type default)
			)
			(layer "F.Fab")
		)
		(fp_line
			(start -0.67945 0.3048)
			(end -0.67945 -0.305054)
			(stroke
				(width 0.1)
				(type default)
			)
			(layer "F.Fab")
		)
		(pad "1" smd circle
			(at -0.40005 0 90)
			(size 0 0)
			(layers "F.Cu" "F.Mask" "F.Paste")
			(net "PVCCIN_CPU1")
		)
		(pad "2" smd circle
			(at 0.40005 0 90)
			(size 0 0)
			(layers "F.Cu" "F.Mask" "F.Paste")
			(net "GND")
		)
	)
	(footprint ""
		(layer "F.Cu")
		(at 459.267814 -379.556772)
		(property "Reference" "PC1877"
			(at 0 0 0)
			(layer "F.SilkS")
			(hide yes)
			(effects
				(font
					(size 1.27 1.27)
				)
			)
		)
		(property "Value" ""
			(at 0 0 0)
			(layer "F.Fab")
			(effects
				(font
					(size 1.27 1.27)
				)
			)
		)
		(duplicate_pad_numbers_are_jumpers no)
		(fp_line
			(start -0.7874 -0.4064)
			(end 0.7874 -0.4064)
			(stroke
				(width 0.1524)
				(type default)
			)
			(layer "F.SilkS")
		)
		(fp_line
			(start -0.7874 0.4064)
			(end -0.7874 -0.4064)
			(stroke
				(width 0.1524)
				(type default)
			)
			(layer "F.SilkS")
		)
		(fp_line
			(start 0.7874 -0.4064)
			(end 0.7874 0.4064)
			(stroke
				(width 0.1524)
				(type default)
			)
			(layer "F.SilkS")
		)
		(fp_line
			(start 0.7874 0.4064)
			(end -0.7874 0.4064)
			(stroke
				(width 0.1524)
				(type default)
			)
			(layer "F.SilkS")
		)
		(fp_line
			(start -0.67945 -0.305054)
			(end -0.12065 -0.305054)
			(stroke
				(width 0.1)
				(type default)
			)
			(layer "F.Fab")
		)
		(fp_line
			(start -0.67945 0.3048)
			(end -0.67945 -0.305054)
			(stroke
				(width 0.1)
				(type default)
			)
			(layer "F.Fab")
		)
		(fp_line
			(start -0.12065 -0.305054)
			(end -0.12065 -0.2794)
			(stroke
				(width 0.1)
				(type default)
			)
			(layer "F.Fab")
		)
		(fp_line
			(start -0.12065 -0.2794)
			(end 0.12065 -0.2794)
			(stroke
				(width 0.1)
				(type default)
			)
			(layer "F.Fab")
		)
		(fp_line
			(start -0.12065 0.2794)
			(end -0.12065 0.3048)
			(stroke
				(width 0.1)
				(type default)
			)
			(layer "F.Fab")
		)
		(fp_line
			(start -0.12065 0.3048)
			(end -0.67945 0.3048)
			(stroke
				(width 0.1)
				(type default)
			)
			(layer "F.Fab")
		)
		(fp_line
			(start 0.120396 0.2794)
			(end -0.12065 0.2794)
			(stroke
				(width 0.1)
				(type default)
			)
			(layer "F.Fab")
		)
		(fp_line
			(start 0.120396 0.3048)
			(end 0.120396 0.2794)
			(stroke
				(width 0.1)
				(type default)
			)
			(layer "F.Fab")
		)
		(fp_line
			(start 0.12065 -0.3048)
			(end 0.67945 -0.3048)
			(stroke
				(width 0.1)
				(type default)
			)
			(layer "F.Fab")
		)
		(fp_line
			(start 0.12065 -0.2794)
			(end 0.12065 -0.3048)
			(stroke
				(width 0.1)
				(type default)
			)
			(layer "F.Fab")
		)
		(fp_line
			(start 0.67945 -0.3048)
			(end 0.67945 0.3048)
			(stroke
				(width 0.1)
				(type default)
			)
			(layer "F.Fab")
		)
		(fp_line
			(start 0.67945 0.3048)
			(end 0.120396 0.3048)
			(stroke
				(width 0.1)
				(type default)
			)
			(layer "F.Fab")
		)
		(pad "1" smd circle
			(at -0.40005 0)
			(size 0 0)
			(layers "F.Cu" "F.Mask" "F.Paste")
			(net "P5V_AUX_FB")
		)
		(pad "2" smd circle
			(at 0.40005 0)
			(size 0 0)
			(layers "F.Cu" "F.Mask" "F.Paste")
			(net "P5V_AUX")
		)
	)
	(footprint ""
		(layer "F.Cu")
		(at 328.123042 -22.674326 -90)
		(property "Reference" "R4098"
			(at 0 0 270)
			(layer "F.SilkS")
			(hide yes)
			(effects
				(font
					(size 1.27 1.27)
				)
			)
		)
		(property "Value" ""
			(at 0 0 270)
			(layer "F.Fab")
			(effects
				(font
					(size 1.27 1.27)
				)
			)
		)
		(duplicate_pad_numbers_are_jumpers no)
		(fp_line
			(start -0.7874 0.4064)
			(end -0.7874 -0.4064)
			(stroke
				(width 0.1524)
				(type default)
			)
			(layer "F.SilkS")
		)
		(fp_line
			(start 0.7874 0.4064)
			(end -0.7874 0.4064)
			(stroke
				(width 0.1524)
				(type default)
			)
			(layer "F.SilkS")
		)
		(fp_line
			(start -0.7874 -0.4064)
			(end 0.7874 -0.4064)
			(stroke
				(width 0.1524)
				(type default)
			)
			(layer "F.SilkS")
		)
		(fp_line
			(start 0.7874 -0.4064)
			(end 0.7874 0.4064)
			(stroke
				(width 0.1524)
				(type default)
			)
			(layer "F.SilkS")
		)
		(fp_line
			(start -0.67945 0.3048)
			(end -0.67945 -0.305054)
			(stroke
				(width 0.1)
				(type default)
			)
			(layer "F.Fab")
		)
		(fp_line
			(start -0.12065 0.3048)
			(end -0.67945 0.3048)
			(stroke
				(width 0.1)
				(type default)
			)
			(layer "F.Fab")
		)
		(fp_line
			(start 0.120396 0.3048)
			(end 0.120396 0.2794)
			(stroke
				(width 0.1)
				(type default)
			)
			(layer "F.Fab")
		)
		(fp_line
			(start 0.67945 0.3048)
			(end 0.120396 0.3048)
			(stroke
				(width 0.1)
				(type default)
			)
			(layer "F.Fab")
		)
		(fp_line
			(start -0.12065 0.2794)
			(end -0.12065 0.3048)
			(stroke
				(width 0.1)
				(type default)
			)
			(layer "F.Fab")
		)
		(fp_line
			(start 0.120396 0.2794)
			(end -0.12065 0.2794)
			(stroke
				(width 0.1)
				(type default)
			)
			(layer "F.Fab")
		)
		(fp_line
			(start -0.12065 -0.2794)
			(end 0.12065 -0.2794)
			(stroke
				(width 0.1)
				(type default)
			)
			(layer "F.Fab")
		)
		(fp_line
			(start 0.12065 -0.2794)
			(end 0.12065 -0.3048)
			(stroke
				(width 0.1)
				(type default)
			)
			(layer "F.Fab")
		)
		(fp_line
			(start 0.12065 -0.3048)
			(end 0.67945 -0.3048)
			(stroke
				(width 0.1)
				(type default)
			)
			(layer "F.Fab")
		)
		(fp_line
			(start 0.67945 -0.3048)
			(end 0.67945 0.3048)
			(stroke
				(width 0.1)
				(type default)
			)
			(layer "F.Fab")
		)
		(fp_line
			(start -0.67945 -0.305054)
			(end -0.12065 -0.305054)
			(stroke
				(width 0.1)
				(type default)
			)
			(layer "F.Fab")
		)
		(fp_line
			(start -0.12065 -0.305054)
			(end -0.12065 -0.2794)
			(stroke
				(width 0.1)
				(type default)
			)
			(layer "F.Fab")
		)
		(pad "1" smd circle
			(at -0.40005 0 270)
			(size 0 0)
			(layers "F.Cu" "F.Mask" "F.Paste")
			(net "PD_PCH_GPPC_A_14")
		)
		(pad "2" smd circle
			(at 0.40005 0 270)
			(size 0 0)
			(layers "F.Cu" "F.Mask" "F.Paste")
			(net "GND")
		)
	)
	(footprint ""
		(layer "F.Cu")
		(at 36.956238 -132.79374)
		(property "Reference" "C2452"
			(at 0 0 0)
			(layer "F.SilkS")
			(hide yes)
			(effects
				(font
					(size 1.27 1.27)
				)
			)
		)
		(property "Value" ""
			(at 0 0 0)
			(layer "F.Fab")
			(effects
				(font
					(size 1.27 1.27)
				)
			)
		)
		(duplicate_pad_numbers_are_jumpers no)
		(fp_line
			(start -0.7874 -0.4064)
			(end 0.7874 -0.4064)
			(stroke
				(width 0.1524)
				(type default)
			)
			(layer "F.SilkS")
		)
		(fp_line
			(start -0.7874 0.4064)
			(end -0.7874 -0.4064)
			(stroke
				(width 0.1524)
				(type default)
			)
			(layer "F.SilkS")
		)
		(fp_line
			(start 0.7874 -0.4064)
			(end 0.7874 0.4064)
			(stroke
				(width 0.1524)
				(type default)
			)
			(layer "F.SilkS")
		)
		(fp_line
			(start 0.7874 0.4064)
			(end -0.7874 0.4064)
			(stroke
				(width 0.1524)
				(type default)
			)
			(layer "F.SilkS")
		)
		(fp_line
			(start -0.67945 -0.305054)
			(end -0.12065 -0.305054)
			(stroke
				(width 0.1)
				(type default)
			)
			(layer "F.Fab")
		)
		(fp_line
			(start -0.67945 0.3048)
			(end -0.67945 -0.305054)
			(stroke
				(width 0.1)
				(type default)
			)
			(layer "F.Fab")
		)
		(fp_line
			(start -0.12065 -0.305054)
			(end -0.12065 -0.2794)
			(stroke
				(width 0.1)
				(type default)
			)
			(layer "F.Fab")
		)
		(fp_line
			(start -0.12065 -0.2794)
			(end 0.12065 -0.2794)
			(stroke
				(width 0.1)
				(type default)
			)
			(layer "F.Fab")
		)
		(fp_line
			(start -0.12065 0.2794)
			(end -0.12065 0.3048)
			(stroke
				(width 0.1)
				(type default)
			)
			(layer "F.Fab")
		)
		(fp_line
			(start -0.12065 0.3048)
			(end -0.67945 0.3048)
			(stroke
				(width 0.1)
				(type default)
			)
			(layer "F.Fab")
		)
		(fp_line
			(start 0.120396 0.2794)
			(end -0.12065 0.2794)
			(stroke
				(width 0.1)
				(type default)
			)
			(layer "F.Fab")
		)
		(fp_line
			(start 0.120396 0.3048)
			(end 0.120396 0.2794)
			(stroke
				(width 0.1)
				(type default)
			)
			(layer "F.Fab")
		)
		(fp_line
			(start 0.12065 -0.3048)
			(end 0.67945 -0.3048)
			(stroke
				(width 0.1)
				(type default)
			)
			(layer "F.Fab")
		)
		(fp_line
			(start 0.12065 -0.2794)
			(end 0.12065 -0.3048)
			(stroke
				(width 0.1)
				(type default)
			)
			(layer "F.Fab")
		)
		(fp_line
			(start 0.67945 -0.3048)
			(end 0.67945 0.3048)
			(stroke
				(width 0.1)
				(type default)
			)
			(layer "F.Fab")
		)
		(fp_line
			(start 0.67945 0.3048)
			(end 0.120396 0.3048)
			(stroke
				(width 0.1)
				(type default)
			)
			(layer "F.Fab")
		)
		(pad "1" smd circle
			(at -0.40005 0)
			(size 0 0)
			(layers "F.Cu" "F.Mask" "F.Paste")
			(net "PVCCFA_EHV_CPU1_EN_R")
		)
		(pad "2" smd circle
			(at 0.40005 0)
			(size 0 0)
			(layers "F.Cu" "F.Mask" "F.Paste")
			(net "GND")
		)
	)
	(footprint ""
		(layer "F.Cu")
		(at 258.192524 -108.154216 90)
		(property "Reference" "R554"
			(at 0 0 90)
			(layer "F.SilkS")
			(hide yes)
			(effects
				(font
					(size 1.27 1.27)
				)
			)
		)
		(property "Value" ""
			(at 0 0 90)
			(layer "F.Fab")
			(effects
				(font
					(size 1.27 1.27)
				)
			)
		)
		(duplicate_pad_numbers_are_jumpers no)
		(fp_line
			(start 0.7874 -0.4064)
			(end 0.7874 0.4064)
			(stroke
				(width 0.1524)
				(type default)
			)
			(layer "F.SilkS")
		)
		(fp_line
			(start -0.7874 -0.4064)
			(end 0.7874 -0.4064)
			(stroke
				(width 0.1524)
				(type default)
			)
			(layer "F.SilkS")
		)
		(fp_line
			(start 0.7874 0.4064)
			(end -0.7874 0.4064)
			(stroke
				(width 0.1524)
				(type default)
			)
			(layer "F.SilkS")
		)
		(fp_line
			(start -0.7874 0.4064)
			(end -0.7874 -0.4064)
			(stroke
				(width 0.1524)
				(type default)
			)
			(layer "F.SilkS")
		)
		(fp_line
			(start -0.12065 -0.305054)
			(end -0.12065 -0.2794)
			(stroke
				(width 0.1)
				(type default)
			)
			(layer "F.Fab")
		)
		(fp_line
			(start -0.67945 -0.305054)
			(end -0.12065 -0.305054)
			(stroke
				(width 0.1)
				(type default)
			)
			(layer "F.Fab")
		)
		(fp_line
			(start 0.67945 -0.3048)
			(end 0.67945 0.3048)
			(stroke
				(width 0.1)
				(type default)
			)
			(layer "F.Fab")
		)
		(fp_line
			(start 0.12065 -0.3048)
			(end 0.67945 -0.3048)
			(stroke
				(width 0.1)
				(type default)
			)
			(layer "F.Fab")
		)
		(fp_line
			(start 0.12065 -0.2794)
			(end 0.12065 -0.3048)
			(stroke
				(width 0.1)
				(type default)
			)
			(layer "F.Fab")
		)
		(fp_line
			(start -0.12065 -0.2794)
			(end 0.12065 -0.2794)
			(stroke
				(width 0.1)
				(type default)
			)
			(layer "F.Fab")
		)
		(fp_line
			(start 0.120396 0.2794)
			(end -0.12065 0.2794)
			(stroke
				(width 0.1)
				(type default)
			)
			(layer "F.Fab")
		)
		(fp_line
			(start -0.12065 0.2794)
			(end -0.12065 0.3048)
			(stroke
				(width 0.1)
				(type default)
			)
			(layer "F.Fab")
		)
		(fp_line
			(start 0.67945 0.3048)
			(end 0.120396 0.3048)
			(stroke
				(width 0.1)
				(type default)
			)
			(layer "F.Fab")
		)
		(fp_line
			(start 0.120396 0.3048)
			(end 0.120396 0.2794)
			(stroke
				(width 0.1)
				(type default)
			)
			(layer "F.Fab")
		)
		(fp_line
			(start -0.12065 0.3048)
			(end -0.67945 0.3048)
			(stroke
				(width 0.1)
				(type default)
			)
			(layer "F.Fab")
		)
		(fp_line
			(start -0.67945 0.3048)
			(end -0.67945 -0.305054)
			(stroke
				(width 0.1)
				(type default)
			)
			(layer "F.Fab")
		)
		(pad "1" smd circle
			(at -0.40005 0 90)
			(size 0 0)
			(layers "F.Cu" "F.Mask" "F.Paste")
			(net "CLK_100M_CK440_PCH_EXTCLK_R_DN")
		)
		(pad "2" smd circle
			(at 0.40005 0 90)
			(size 0 0)
			(layers "F.Cu" "F.Mask" "F.Paste")
			(net "CLK_100M_CK440_PCH_EXTCLK_DN")
		)
	)
	(footprint ""
		(layer "F.Cu")
		(at 39.80688 -435.955948)
		(property "Reference" "R2899"
			(at 0 0 0)
			(layer "F.SilkS")
			(hide yes)
			(effects
				(font
					(size 1.27 1.27)
				)
			)
		)
		(property "Value" ""
			(at 0 0 0)
			(layer "F.Fab")
			(effects
				(font
					(size 1.27 1.27)
				)
			)
		)
		(duplicate_pad_numbers_are_jumpers no)
		(fp_line
			(start -0.7874 -0.4064)
			(end 0.7874 -0.4064)
			(stroke
				(width 0.1524)
				(type default)
			)
			(layer "F.SilkS")
		)
		(fp_line
			(start -0.7874 0.4064)
			(end -0.7874 -0.4064)
			(stroke
				(width 0.1524)
				(type default)
			)
			(layer "F.SilkS")
		)
		(fp_line
			(start 0.7874 -0.4064)
			(end 0.7874 0.4064)
			(stroke
				(width 0.1524)
				(type default)
			)
			(layer "F.SilkS")
		)
		(fp_line
			(start 0.7874 0.4064)
			(end -0.7874 0.4064)
			(stroke
				(width 0.1524)
				(type default)
			)
			(layer "F.SilkS")
		)
		(fp_line
			(start -0.67945 -0.305054)
			(end -0.12065 -0.305054)
			(stroke
				(width 0.1)
				(type default)
			)
			(layer "F.Fab")
		)
		(fp_line
			(start -0.67945 0.3048)
			(end -0.67945 -0.305054)
			(stroke
				(width 0.1)
				(type default)
			)
			(layer "F.Fab")
		)
		(fp_line
			(start -0.12065 -0.305054)
			(end -0.12065 -0.2794)
			(stroke
				(width 0.1)
				(type default)
			)
			(layer "F.Fab")
		)
		(fp_line
			(start -0.12065 -0.2794)
			(end 0.12065 -0.2794)
			(stroke
				(width 0.1)
				(type default)
			)
			(layer "F.Fab")
		)
		(fp_line
			(start -0.12065 0.2794)
			(end -0.12065 0.3048)
			(stroke
				(width 0.1)
				(type default)
			)
			(layer "F.Fab")
		)
		(fp_line
			(start -0.12065 0.3048)
			(end -0.67945 0.3048)
			(stroke
				(width 0.1)
				(type default)
			)
			(layer "F.Fab")
		)
		(fp_line
			(start 0.120396 0.2794)
			(end -0.12065 0.2794)
			(stroke
				(width 0.1)
				(type default)
			)
			(layer "F.Fab")
		)
		(fp_line
			(start 0.120396 0.3048)
			(end 0.120396 0.2794)
			(stroke
				(width 0.1)
				(type default)
			)
			(layer "F.Fab")
		)
		(fp_line
			(start 0.12065 -0.3048)
			(end 0.67945 -0.3048)
			(stroke
				(width 0.1)
				(type default)
			)
			(layer "F.Fab")
		)
		(fp_line
			(start 0.12065 -0.2794)
			(end 0.12065 -0.3048)
			(stroke
				(width 0.1)
				(type default)
			)
			(layer "F.Fab")
		)
		(fp_line
			(start 0.67945 -0.3048)
			(end 0.67945 0.3048)
			(stroke
				(width 0.1)
				(type default)
			)
			(layer "F.Fab")
		)
		(fp_line
			(start 0.67945 0.3048)
			(end 0.120396 0.3048)
			(stroke
				(width 0.1)
				(type default)
			)
			(layer "F.Fab")
		)
		(pad "1" smd circle
			(at -0.40005 0)
			(size 0 0)
			(layers "F.Cu" "F.Mask" "F.Paste")
			(net "SMB_BMC_GPU_EN")
		)
		(pad "2" smd circle
			(at 0.40005 0)
			(size 0 0)
			(layers "F.Cu" "F.Mask" "F.Paste")
			(net "SMB_BMC_GPU_EN_R1")
		)
	)
)
